(kicad_pcb
	(version 20241229)
	(generator "pcbnew")
	(generator_version "9.0")
	(general
		(thickness 1.6642)
		(legacy_teardrops no)
	)
	(paper "A3")
	(title_block
		(title "PolarFire SoM")
		(date "2025-07-22")
		(rev "1.1.4")
		(company "Antmicro Ltd")
		(comment 1 "www.antmicro.com")
		(comment 9 "footprints 263-266 of 470")
	)
	(layers
		(0 "F.Cu" mixed)
		(4 "In1.Cu" power)
		(6 "In2.Cu" signal)
		(8 "In3.Cu" power)
		(10 "In4.Cu" signal)
		(12 "In5.Cu" power)
		(14 "In6.Cu" power)
		(16 "In7.Cu" signal)
		(18 "In8.Cu" power)
		(20 "In9.Cu" signal)
		(22 "In10.Cu" power)
		(24 "In11.Cu" signal)
		(26 "In12.Cu" signal)
		(2 "B.Cu" mixed)
		(9 "F.Adhes" user "F.Adhesive")
		(11 "B.Adhes" user "B.Adhesive")
		(13 "F.Paste" user)
		(15 "B.Paste" user)
		(5 "F.SilkS" user "F.Silkscreen")
		(7 "B.SilkS" user "B.Silkscreen")
		(1 "F.Mask" user)
		(3 "B.Mask" user)
		(17 "Dwgs.User" user "User.Drawings")
		(19 "Cmts.User" user "User.Comments")
		(21 "Eco1.User" user "User.Eco1")
		(23 "Eco2.User" user "User.Eco2")
		(25 "Edge.Cuts" user)
		(27 "Margin" user)
		(31 "F.CrtYd" user "F.Courtyard")
		(29 "B.CrtYd" user "B.Courtyard")
		(35 "F.Fab" user)
		(33 "B.Fab" user)
	)
	(footprint "antmicro-footprints:C_0402_1005Metric"
		(layer "B.Cu")
		(at 215.1925 130.697 180)
		(descr "Capacitor SMD 0402")
		(tags "capacitor SMD 0402")
		(property "Reference" "C71"
			(at -2.9975 -0.433 0)
			(layer "B.SilkS")
			(effects
				(font
					(size 0.7 0.7)
					(thickness 0.15)
				)
				(justify left bottom mirror)
			)
		)
		(property "Value" "C_100n_0402"
			(at -1.022927 -2.155213 0)
			(layer "B.Fab")
			(hide yes)
			(effects
				(font
					(size 0.7 0.7)
					(thickness 0.15)
				)
				(justify left bottom mirror)
			)
		)
		(property "Datasheet" "https://www.murata.com/products/productdetail?partno=GRM155R61H104KE14%23"
			(at 0 0 180)
			(layer "F.Fab")
			(hide yes)
			(effects
				(font
					(size 1.27 1.27)
					(thickness 0.15)
				)
			)
		)
		(property "Description" "SMD Multilayer Ceramic Capacitor, 0.1 µF, 50 V, 0402 [1005 Metric], ± 10%, X5R, GRM Series"
			(at 0 0 180)
			(layer "F.Fab")
			(hide yes)
			(effects
				(font
					(size 1.27 1.27)
					(thickness 0.15)
				)
			)
		)
		(property "Author" "Antmicro"
			(at 430.385 261.394 0)
			(layer "B.Fab")
			(hide yes)
			(effects
				(font
					(size 1 1)
					(thickness 0.15)
				)
				(justify mirror)
			)
		)
		(property "Dielectric" "X5R"
			(at 430.385 261.394 0)
			(layer "B.Fab")
			(hide yes)
			(effects
				(font
					(size 1 1)
					(thickness 0.15)
				)
				(justify mirror)
			)
		)
		(property "License" "Apache-2.0"
			(at 430.385 261.394 0)
			(layer "B.Fab")
			(hide yes)
			(effects
				(font
					(size 1 1)
					(thickness 0.15)
				)
				(justify mirror)
			)
		)
		(property "MPN" "GRM155R61H104KE14D"
			(at 430.385 261.394 0)
			(layer "B.Fab")
			(hide yes)
			(effects
				(font
					(size 1 1)
					(thickness 0.15)
				)
				(justify mirror)
			)
		)
		(property "Manufacturer" "Murata"
			(at 430.385 261.394 0)
			(layer "B.Fab")
			(hide yes)
			(effects
				(font
					(size 1 1)
					(thickness 0.15)
				)
				(justify mirror)
			)
		)
		(property "Public" ""
			(at 430.385 261.394 0)
			(layer "B.Fab")
			(hide yes)
			(effects
				(font
					(size 1 1)
					(thickness 0.15)
				)
				(justify mirror)
			)
		)
		(property "Val" "100n"
			(at 430.385 261.394 0)
			(layer "B.Fab")
			(hide yes)
			(effects
				(font
					(size 1 1)
					(thickness 0.15)
				)
				(justify mirror)
			)
		)
		(property "Voltage" "50V"
			(at 430.385 261.394 0)
			(layer "B.Fab")
			(hide yes)
			(effects
				(font
					(size 1 1)
					(thickness 0.15)
				)
				(justify mirror)
			)
		)
		(sheetname "/Memory/")
		(sheetfile "memory.kicad_sch")
		(attr smd)
		(fp_rect
			(start -0.925 0.47)
			(end 0.925 -0.47)
			(stroke
				(width 0.05)
				(type default)
			)
			(fill no)
			(layer "B.CrtYd")
		)
		(fp_line
			(start 0.504 0.25)
			(end 0.504 -0.248)
			(stroke
				(width 0.15)
				(type solid)
			)
			(layer "B.Fab")
		)
		(fp_line
			(start 0.504 -0.248)
			(end -0.494 -0.248)
			(stroke
				(width 0.15)
				(type solid)
			)
			(layer "B.Fab")
		)
		(fp_line
			(start -0.494 0.25)
			(end 0.504 0.25)
			(stroke
				(width 0.15)
				(type solid)
			)
			(layer "B.Fab")
		)
		(fp_line
			(start -0.494 -0.248)
			(end -0.494 0.25)
			(stroke
				(width 0.15)
				(type solid)
			)
			(layer "B.Fab")
		)
		(fp_text user "Author: Antmicro"
			(at -0.939 -3.399 0)
			(layer "B.Fab")
			(effects
				(font
					(size 0.7 0.7)
					(thickness 0.15)
				)
				(justify left bottom mirror)
			)
		)
		(fp_text user "${REFERENCE}"
			(at -0.939 -4.599 0)
			(layer "B.Fab")
			(effects
				(font
					(size 0.7 0.7)
					(thickness 0.15)
				)
				(justify left bottom mirror)
			)
		)
		(fp_text user "License: Apache-2.0"
			(at -0.939 -5.799 0)
			(layer "B.Fab")
			(effects
				(font
					(size 0.7 0.7)
					(thickness 0.15)
				)
				(justify left bottom mirror)
			)
		)
		(pad "1" smd roundrect
			(at -0.48 0 180)
			(size 0.59 0.64)
			(layers "B.Cu" "B.Mask" "B.Paste")
			(roundrect_rratio 0.25)
			(net 417 "GND")
			(pintype "passive")
		)
		(pad "2" smd roundrect
			(at 0.48 0 180)
			(size 0.59 0.64)
			(layers "B.Cu" "B.Mask" "B.Paste")
			(roundrect_rratio 0.25)
			(net 50 "+3V3")
			(pintype "passive")
		)
	)
	(footprint "antmicro-footprints:R_0402_1005Metric"
		(layer "B.Cu")
		(at 182.3 152.05 -90)
		(descr "Resistor SMD 0402")
		(tags "resistor SMD 0402")
		(property "Reference" "R16"
			(at -2.95 -0.3 90)
			(layer "B.SilkS")
			(effects
				(font
					(size 0.7 0.7)
					(thickness 0.15)
				)
				(justify left bottom mirror)
			)
		)
		(property "Value" "R_10k_0402"
			(at -1.011843 -1.772047 90)
			(layer "B.Fab")
			(hide yes)
			(effects
				(font
					(size 0.7 0.7)
					(thickness 0.15)
				)
				(justify left bottom mirror)
			)
		)
		(property "Datasheet" "https://www.bourns.com/docs/product-datasheets/cr.pdf"
			(at 0 0 270)
			(layer "F.Fab")
			(hide yes)
			(effects
				(font
					(size 1.27 1.27)
					(thickness 0.15)
				)
			)
		)
		(property "Description" "SMD Chip Resistor, 10 kohm, ± 1%, 62.5 mW, 0402 [1005 Metric], Thick Film, General Purpose"
			(at 0 0 270)
			(layer "F.Fab")
			(hide yes)
			(effects
				(font
					(size 1.27 1.27)
					(thickness 0.15)
				)
			)
		)
		(property "Author" "Antmicro"
			(at 30.25 334.35 0)
			(layer "B.Fab")
			(hide yes)
			(effects
				(font
					(size 1 1)
					(thickness 0.15)
				)
				(justify mirror)
			)
		)
		(property "License" "Apache-2.0"
			(at 30.25 334.35 0)
			(layer "B.Fab")
			(hide yes)
			(effects
				(font
					(size 1 1)
					(thickness 0.15)
				)
				(justify mirror)
			)
		)
		(property "MPN" "CR0402-FX-1002GLF"
			(at 30.25 334.35 0)
			(layer "B.Fab")
			(hide yes)
			(effects
				(font
					(size 1 1)
					(thickness 0.15)
				)
				(justify mirror)
			)
		)
		(property "Manufacturer" "Bourns"
			(at 30.25 334.35 0)
			(layer "B.Fab")
			(hide yes)
			(effects
				(font
					(size 1 1)
					(thickness 0.15)
				)
				(justify mirror)
			)
		)
		(property "Public" ""
			(at 30.25 334.35 0)
			(layer "B.Fab")
			(hide yes)
			(effects
				(font
					(size 1 1)
					(thickness 0.15)
				)
				(justify mirror)
			)
		)
		(property "Tolerance" "1%"
			(at 30.25 334.35 0)
			(layer "B.Fab")
			(hide yes)
			(effects
				(font
					(size 1 1)
					(thickness 0.15)
				)
				(justify mirror)
			)
		)
		(property "Val" "10k"
			(at 30.25 334.35 0)
			(layer "B.Fab")
			(hide yes)
			(effects
				(font
					(size 1 1)
					(thickness 0.15)
				)
				(justify mirror)
			)
		)
		(sheetname "/Supply/")
		(sheetfile "supply.kicad_sch")
		(attr smd)
		(fp_rect
			(start -0.925 0.47)
			(end 0.925 -0.47)
			(stroke
				(width 0.05)
				(type default)
			)
			(fill no)
			(layer "B.CrtYd")
		)
		(fp_rect
			(start -0.5 0.25)
			(end 0.5 -0.25)
			(stroke
				(width 0.15)
				(type solid)
			)
			(fill no)
			(layer "B.Fab")
		)
		(fp_text user "${REFERENCE}"
			(at -0.95 -3.168 90)
			(layer "B.Fab")
			(effects
				(font
					(size 0.7 0.7)
					(thickness 0.15)
				)
				(justify left bottom mirror)
			)
		)
		(fp_text user "License: Apache-2.0"
			(at -0.95 -5.169 90)
			(layer "B.Fab")
			(effects
				(font
					(size 0.7 0.7)
					(thickness 0.15)
				)
				(justify left bottom mirror)
			)
		)
		(fp_text user "Author: Antmicro"
			(at -0.95 -4.169 90)
			(layer "B.Fab")
			(effects
				(font
					(size 0.7 0.7)
					(thickness 0.15)
				)
				(justify left bottom mirror)
			)
		)
		(pad "1" smd roundrect
			(at -0.48 0 270)
			(size 0.59 0.64)
			(layers "B.Cu" "B.Mask" "B.Paste")
			(roundrect_rratio 0.25)
			(net 398 "/Supply/1V05_FB")
			(pintype "passive")
		)
		(pad "2" smd roundrect
			(at 0.48 0 270)
			(size 0.59 0.64)
			(layers "B.Cu" "B.Mask" "B.Paste")
			(roundrect_rratio 0.25)
			(net 14 "Net-(C111-Pad1)")
			(pintype "passive")
		)
	)
	(footprint "antmicro-footprints:C_0402_1005Metric"
		(layer "B.Cu")
		(at 204.01 129.25 180)
		(descr "Capacitor SMD 0402")
		(tags "capacitor SMD 0402")
		(property "Reference" "C11"
			(at -1.465 0.55 0)
			(layer "B.SilkS")
			(effects
				(font
					(size 0.7 0.7)
					(thickness 0.15)
				)
				(justify left bottom mirror)
			)
		)
		(property "Value" "C_10u_0402"
			(at -1.022927 -2.155213 0)
			(layer "B.Fab")
			(hide yes)
			(effects
				(font
					(size 0.7 0.7)
					(thickness 0.15)
				)
				(justify left bottom mirror)
			)
		)
		(property "Datasheet" "https://www.yageo.com/en/Chart/Download/pdf/CC0402MRX5R5BB106"
			(at 0 0 180)
			(layer "F.Fab")
			(hide yes)
			(effects
				(font
					(size 1.27 1.27)
					(thickness 0.15)
				)
			)
		)
		(property "Description" "SMD Multilayer Ceramic Capacitor, 10 µF, 6.3 V, 0402 [1005 Metric], ± 20%, X5R, CC Series"
			(at 0 0 180)
			(layer "F.Fab")
			(hide yes)
			(effects
				(font
					(size 1.27 1.27)
					(thickness 0.15)
				)
			)
		)
		(property "Author" "Antmicro"
			(at 408.02 258.5 0)
			(layer "B.Fab")
			(hide yes)
			(effects
				(font
					(size 1 1)
					(thickness 0.15)
				)
				(justify mirror)
			)
		)
		(property "Dielectric" ""
			(at 408.02 258.5 0)
			(layer "B.Fab")
			(hide yes)
			(effects
				(font
					(size 1 1)
					(thickness 0.15)
				)
				(justify mirror)
			)
		)
		(property "License" "Apache-2.0"
			(at 408.02 258.5 0)
			(layer "B.Fab")
			(hide yes)
			(effects
				(font
					(size 1 1)
					(thickness 0.15)
				)
				(justify mirror)
			)
		)
		(property "MPN" "CC0402MRX5R5BB106"
			(at 408.02 258.5 0)
			(layer "B.Fab")
			(hide yes)
			(effects
				(font
					(size 1 1)
					(thickness 0.15)
				)
				(justify mirror)
			)
		)
		(property "Manufacturer" "YAGEO"
			(at 408.02 258.5 0)
			(layer "B.Fab")
			(hide yes)
			(effects
				(font
					(size 1 1)
					(thickness 0.15)
				)
				(justify mirror)
			)
		)
		(property "Public" ""
			(at 408.02 258.5 0)
			(layer "B.Fab")
			(hide yes)
			(effects
				(font
					(size 1 1)
					(thickness 0.15)
				)
				(justify mirror)
			)
		)
		(property "Val" "10u"
			(at 408.02 258.5 0)
			(layer "B.Fab")
			(hide yes)
			(effects
				(font
					(size 1 1)
					(thickness 0.15)
				)
				(justify mirror)
			)
		)
		(property "Voltage" ""
			(at 408.02 258.5 0)
			(layer "B.Fab")
			(hide yes)
			(effects
				(font
					(size 1 1)
					(thickness 0.15)
				)
				(justify mirror)
			)
		)
		(sheetname "/FPGA Supply/")
		(sheetfile "fpga-supply.kicad_sch")
		(attr smd)
		(fp_rect
			(start -0.925 0.47)
			(end 0.925 -0.47)
			(stroke
				(width 0.05)
				(type default)
			)
			(fill no)
			(layer "B.CrtYd")
		)
		(fp_line
			(start 0.504 0.25)
			(end 0.504 -0.248)
			(stroke
				(width 0.15)
				(type solid)
			)
			(layer "B.Fab")
		)
		(fp_line
			(start 0.504 -0.248)
			(end -0.494 -0.248)
			(stroke
				(width 0.15)
				(type solid)
			)
			(layer "B.Fab")
		)
		(fp_line
			(start -0.494 0.25)
			(end 0.504 0.25)
			(stroke
				(width 0.15)
				(type solid)
			)
			(layer "B.Fab")
		)
		(fp_line
			(start -0.494 -0.248)
			(end -0.494 0.25)
			(stroke
				(width 0.15)
				(type solid)
			)
			(layer "B.Fab")
		)
		(fp_text user "Author: Antmicro"
			(at -0.939 -3.399 0)
			(layer "B.Fab")
			(effects
				(font
					(size 0.7 0.7)
					(thickness 0.15)
				)
				(justify left bottom mirror)
			)
		)
		(fp_text user "License: Apache-2.0"
			(at -0.939 -5.799 0)
			(layer "B.Fab")
			(effects
				(font
					(size 0.7 0.7)
					(thickness 0.15)
				)
				(justify left bottom mirror)
			)
		)
		(fp_text user "${REFERENCE}"
			(at -0.939 -4.599 0)
			(layer "B.Fab")
			(effects
				(font
					(size 0.7 0.7)
					(thickness 0.15)
				)
				(justify left bottom mirror)
			)
		)
		(pad "1" smd roundrect
			(at -0.48 0 180)
			(size 0.59 0.64)
			(layers "B.Cu" "B.Mask" "B.Paste")
			(roundrect_rratio 0.25)
			(net 417 "GND")
			(pintype "passive")
		)
		(pad "2" smd roundrect
			(at 0.48 0 180)
			(size 0.59 0.64)
			(layers "B.Cu" "B.Mask" "B.Paste")
			(roundrect_rratio 0.25)
			(net 50 "+3V3")
			(pintype "passive")
		)
	)
	(footprint "antmicro-footprints:C_0402_1005Metric"
		(layer "B.Cu")
		(at 178.8 127 180)
		(descr "Capacitor SMD 0402")
		(tags "capacitor SMD 0402")
		(property "Reference" "C121"
			(at -1.54 -1.375 0)
			(layer "B.SilkS")
			(effects
				(font
					(size 0.7 0.7)
					(thickness 0.15)
				)
				(justify left bottom mirror)
			)
		)
		(property "Value" "C_1u_0402"
			(at -1.022927 -2.155213 0)
			(layer "B.Fab")
			(hide yes)
			(effects
				(font
					(size 0.7 0.7)
					(thickness 0.15)
				)
				(justify left bottom mirror)
			)
		)
		(property "Datasheet" "https://product.tdk.com/en/search/capacitor/ceramic/mlcc/info?part_no=C1005X6S1A105K050BC"
			(at 0 0 180)
			(layer "F.Fab")
			(hide yes)
			(effects
				(font
					(size 1.27 1.27)
					(thickness 0.15)
				)
			)
		)
		(property "Description" "SMD Multilayer Ceramic Capacitor, 1 µF, 10 V, 0402 [1005 Metric], ± 10%, X6S, C"
			(at 0 0 180)
			(layer "F.Fab")
			(hide yes)
			(effects
				(font
					(size 1.27 1.27)
					(thickness 0.15)
				)
			)
		)
		(property "Author" "Antmicro"
			(at 357.6 254 0)
			(layer "B.Fab")
			(hide yes)
			(effects
				(font
					(size 1 1)
					(thickness 0.15)
				)
				(justify mirror)
			)
		)
		(property "Dielectric" "X5R"
			(at 357.6 254 0)
			(layer "B.Fab")
			(hide yes)
			(effects
				(font
					(size 1 1)
					(thickness 0.15)
				)
				(justify mirror)
			)
		)
		(property "License" "Apache-2.0"
			(at 357.6 254 0)
			(layer "B.Fab")
			(hide yes)
			(effects
				(font
					(size 1 1)
					(thickness 0.15)
				)
				(justify mirror)
			)
		)
		(property "MPN" "C1005X6S1A105K050BC"
			(at 357.6 254 0)
			(layer "B.Fab")
			(hide yes)
			(effects
				(font
					(size 1 1)
					(thickness 0.15)
				)
				(justify mirror)
			)
		)
		(property "Manufacturer" "TDK"
			(at 357.6 254 0)
			(layer "B.Fab")
			(hide yes)
			(effects
				(font
					(size 1 1)
					(thickness 0.15)
				)
				(justify mirror)
			)
		)
		(property "Public" ""
			(at 357.6 254 0)
			(layer "B.Fab")
			(hide yes)
			(effects
				(font
					(size 1 1)
					(thickness 0.15)
				)
				(justify mirror)
			)
		)
		(property "Val" "1u"
			(at 357.6 254 0)
			(layer "B.Fab")
			(hide yes)
			(effects
				(font
					(size 1 1)
					(thickness 0.15)
				)
				(justify mirror)
			)
		)
		(property "Voltage" "16V"
			(at 357.6 254 0)
			(layer "B.Fab")
			(hide yes)
			(effects
				(font
					(size 1 1)
					(thickness 0.15)
				)
				(justify mirror)
			)
		)
		(sheetname "/LPDDR4/")
		(sheetfile "lpddr.kicad_sch")
		(attr smd)
		(fp_rect
			(start -0.925 0.47)
			(end 0.925 -0.47)
			(stroke
				(width 0.05)
				(type default)
			)
			(fill no)
			(layer "B.CrtYd")
		)
		(fp_line
			(start 0.504 0.25)
			(end 0.504 -0.248)
			(stroke
				(width 0.15)
				(type solid)
			)
			(layer "B.Fab")
		)
		(fp_line
			(start 0.504 -0.248)
			(end -0.494 -0.248)
			(stroke
				(width 0.15)
				(type solid)
			)
			(layer "B.Fab")
		)
		(fp_line
			(start -0.494 0.25)
			(end 0.504 0.25)
			(stroke
				(width 0.15)
				(type solid)
			)
			(layer "B.Fab")
		)
		(fp_line
			(start -0.494 -0.248)
			(end -0.494 0.25)
			(stroke
				(width 0.15)
				(type solid)
			)
			(layer "B.Fab")
		)
		(fp_text user "Author: Antmicro"
			(at -0.939 -3.399 0)
			(layer "B.Fab")
			(effects
				(font
					(size 0.7 0.7)
					(thickness 0.15)
				)
				(justify left bottom mirror)
			)
		)
		(fp_text user "License: Apache-2.0"
			(at -0.939 -5.799 0)
			(layer "B.Fab")
			(effects
				(font
					(size 0.7 0.7)
					(thickness 0.15)
				)
				(justify left bottom mirror)
			)
		)
		(fp_text user "${REFERENCE}"
			(at -0.939 -4.599 0)
			(layer "B.Fab")
			(effects
				(font
					(size 0.7 0.7)
					(thickness 0.15)
				)
				(justify left bottom mirror)
			)
		)
		(pad "1" smd roundrect
			(at -0.48 0 180)
			(size 0.59 0.64)
			(layers "B.Cu" "B.Mask" "B.Paste")
			(roundrect_rratio 0.25)
			(net 417 "GND")
			(pintype "passive")
		)
		(pad "2" smd roundrect
			(at 0.48 0 180)
			(size 0.59 0.64)
			(layers "B.Cu" "B.Mask" "B.Paste")
			(roundrect_rratio 0.25)
			(net 48 "+1V8")
			(pintype "passive")
		)
	)
)
